(kicad_pcb
	(version 20260206)
	(generator "pcbnew")
	(generator_version "10.0")
	(general
		(thickness 1.6)
		(legacy_teardrops no)
	)
	(paper "A4")
	(title_block
		(title "Bryce Canyon_IOM_IOC_16318-2_OCP.brd")
		(comment 1 "Bryce Canyon / footprints 804-809 of 1605")
	)
	(layers
		(0 "F.Cu" signal "TOP")
		(4 "In1.Cu" signal "L2GND")
		(6 "In2.Cu" signal "L3")
		(8 "In3.Cu" signal "L4VCC")
		(10 "In4.Cu" signal "L5VCC")
		(12 "In5.Cu" signal "L6")
		(14 "In6.Cu" signal "L7GND")
		(2 "B.Cu" signal "BOTTOM")
		(9 "F.Adhes" user "F.Adhesive")
		(11 "B.Adhes" user "B.Adhesive")
		(13 "F.Paste" user "Package Geometry/Pastemask Top")
		(15 "B.Paste" user "Package Geometry/Pastemask Bottom")
		(5 "F.SilkS" user "Ref Des/Silkscreen Top")
		(7 "B.SilkS" user "Ref Des/Silkscreen Bottom")
		(1 "F.Mask" user "Board Geometry/Soldermask Top")
		(3 "B.Mask" user "Board Geometry/Soldermask Bottom")
		(17 "Dwgs.User" user "User.Drawings")
		(19 "Cmts.User" user "User.Comments")
		(21 "Eco1.User" user "User.Eco1")
		(23 "Eco2.User" user "User.Eco2")
		(25 "Edge.Cuts" user "Board Geometry/Outline")
		(27 "Margin" user)
		(31 "F.CrtYd" user "Package Geometry/Place Bound Top")
		(29 "B.CrtYd" user "Package Geometry/Place Bound Bottom")
		(35 "F.Fab" user "Ref Des/Assembly Top")
		(33 "B.Fab" user "Ref Des/Assembly Bottom")
	)
	(footprint ""
		(layer "F.Cu")
		(at 50.27168 -184.020714)
		(property "Reference" "C175"
			(at 0 0 0)
			(layer "F.SilkS")
			(hide yes)
			(effects
				(font
					(size 1.27 1.27)
				)
			)
		)
		(property "Value" "ST150U6D3VDM-28-GP"
			(at 0 -9.6012 0)
			(unlocked yes)
			(layer "F.Fab")
			(hide yes)
			(effects
				(font
					(size 1.016 1.016)
					(thickness 0.1524)
				)
			)
		)
		(property "Device Type" "CT7343H83"
			(at 0 -11.1252 0)
			(unlocked yes)
			(layer "F.Fab")
			(hide yes)
			(effects
				(font
					(size 1.016 1.016)
					(thickness 0.1524)
				)
			)
		)
		(duplicate_pad_numbers_are_jumpers no)
		(fp_line
			(start -2.286 -4.8768)
			(end -2.286 -2.032)
			(stroke
				(width 0.1524)
				(type default)
			)
			(layer "F.SilkS")
		)
		(fp_line
			(start -2.286 4.8768)
			(end -2.286 2.032)
			(stroke
				(width 0.1524)
				(type default)
			)
			(layer "F.SilkS")
		)
		(fp_line
			(start 2.1082 -4.699)
			(end -2.1082 -4.699)
			(stroke
				(width 0.508)
				(type default)
			)
			(layer "F.SilkS")
		)
		(fp_line
			(start 2.286 -4.8768)
			(end -2.286 -4.8768)
			(stroke
				(width 0.1524)
				(type default)
			)
			(layer "F.SilkS")
		)
		(fp_line
			(start 2.286 -2.032)
			(end 2.286 -4.8768)
			(stroke
				(width 0.1524)
				(type default)
			)
			(layer "F.SilkS")
		)
		(fp_line
			(start 2.286 2.032)
			(end 2.286 4.8768)
			(stroke
				(width 0.1524)
				(type default)
			)
			(layer "F.SilkS")
		)
		(fp_line
			(start 2.286 4.8768)
			(end -2.286 4.8768)
			(stroke
				(width 0.1524)
				(type default)
			)
			(layer "F.SilkS")
		)
		(fp_rect
			(start -2.1463 3.6449)
			(end 2.1463 -3.6449)
			(stroke
				(width 0)
				(type default)
			)
			(fill no)
			(layer "F.CrtYd")
		)
		(fp_poly
			(pts
				(xy -2.54 4.953) (xy -2.54 4.2926) (xy -3.81 4.2926) (xy -3.81 -4.2926) (xy -2.54 -4.2926) (xy -2.54 -4.953)
				(xy 2.54 -4.953) (xy 2.54 -4.2926) (xy 3.81 -4.2926) (xy 3.81 -1.6256) (xy 2.1463 -1.6256) (xy 2.1463 -3.6449)
				(xy -2.1463 -3.6449) (xy -2.1463 3.6449) (xy 2.1463 3.6449) (xy 2.1463 -1.6129) (xy 3.81 -1.6129)
				(xy 3.81 4.2926) (xy 2.54 4.2926) (xy 2.54 4.953)
			)
			(stroke
				(width 0)
				(type default)
			)
			(fill no)
			(layer "F.CrtYd")
		)
		(fp_rect
			(start -3.81 4.2926)
			(end -2.54 -4.2926)
			(stroke
				(width 0)
				(type default)
			)
			(fill no)
			(layer "F.Fab")
		)
		(fp_rect
			(start -2.54 4.953)
			(end 2.54 -4.953)
			(stroke
				(width 0)
				(type default)
			)
			(fill no)
			(layer "F.Fab")
		)
		(fp_rect
			(start 2.54 4.2926)
			(end 3.81 -4.2926)
			(stroke
				(width 0)
				(type default)
			)
			(fill no)
			(layer "F.Fab")
		)
		(pad "1" smd rect
			(at 0 -3.1496)
			(size 2.413 2.286)
			(layers "F.Cu" "F.Mask" "F.Paste")
			(net "P3V3_STBY_OUT")
		)
		(pad "2" smd rect
			(at 0 3.1496)
			(size 2.413 2.286)
			(layers "F.Cu" "F.Mask" "F.Paste")
			(net "GND")
		)
		(zone
			(layer "F.Cu")
			(hatch none 0.5)
			(connect_pads
				(clearance 0)
			)
			(min_thickness 0.25)
			(keepout
				(tracks allowed)
				(vias not_allowed)
				(pads allowed)
				(copperpour not_allowed)
				(footprints allowed)
			)
			(placement
				(enabled no)
				(sheetname "")
			)
			(fill
				(thermal_gap 0.5)
				(thermal_bridge_width 0.5)
				(island_removal_mode 0)
			)
			(polygon
				(pts
					(xy 48.76038 -179.423314) (xy 51.78298 -179.423314) (xy 51.78298 -182.318914) (xy 51.78298 -182.649114)
					(xy 48.76038 -182.649114) (xy 48.76038 -182.318914)
				)
			)
		)
		(zone
			(layer "F.Cu")
			(hatch none 0.5)
			(connect_pads
				(clearance 0)
			)
			(min_thickness 0.25)
			(keepout
				(tracks allowed)
				(vias not_allowed)
				(pads allowed)
				(copperpour not_allowed)
				(footprints allowed)
			)
			(placement
				(enabled no)
				(sheetname "")
			)
			(fill
				(thermal_gap 0.5)
				(thermal_bridge_width 0.5)
				(island_removal_mode 0)
			)
			(polygon
				(pts
					(xy 51.78298 -185.709814) (xy 51.78298 -188.618114) (xy 48.76038 -188.618114) (xy 48.76038 -185.722514)
					(xy 48.76038 -185.392314) (xy 51.78298 -185.392314)
				)
			)
		)
	)
	(footprint ""
		(layer "F.Cu")
		(at 88.5444 -161.8742 180)
		(property "Reference" "R28"
			(at 0 0 180)
			(layer "F.SilkS")
			(hide yes)
			(effects
				(font
					(size 1.27 1.27)
				)
			)
		)
		(property "Value" "12KR2J-L-GP"
			(at 0.064008 -3.993896 180)
			(unlocked yes)
			(layer "F.Fab")
			(hide yes)
			(effects
				(font
					(size 1.016 1.016)
					(thickness 0.1524)
				)
			)
		)
		(property "Device Type" "R402H16"
			(at 0.064008 -5.517896 180)
			(unlocked yes)
			(layer "F.Fab")
			(hide yes)
			(effects
				(font
					(size 1.016 1.016)
					(thickness 0.1524)
				)
			)
		)
		(duplicate_pad_numbers_are_jumpers no)
		(fp_line
			(start 0.508 -0.9398)
			(end -0.508 -0.9398)
			(stroke
				(width 0.1524)
				(type default)
			)
			(layer "F.SilkS")
		)
		(fp_line
			(start -0.508 -0.9398)
			(end -0.508 0.9398)
			(stroke
				(width 0.1524)
				(type default)
			)
			(layer "F.SilkS")
		)
		(fp_rect
			(start -0.508 0.9398)
			(end 0.508 -0.9398)
			(stroke
				(width 0)
				(type default)
			)
			(fill no)
			(layer "F.CrtYd")
		)
		(fp_rect
			(start -0.508 0.9398)
			(end 0.508 -0.9398)
			(stroke
				(width 0)
				(type default)
			)
			(fill no)
			(layer "F.Fab")
		)
		(pad "1" smd custom
			(at 0 -0.4445 180)
			(size 0.1397 0.1397)
			(layers "F.Cu" "F.Mask" "F.Paste")
			(net "RBIAS")
			(options
				(clearance outline)
				(anchor circle)
			)
			(primitives
				(gr_poly
					(pts
						(arc
							(start -0.1778 -0.2794)
							(mid -0.249642 -0.249642)
							(end -0.2794 -0.1778)
						)
						(arc
							(start -0.2794 0.1778)
							(mid -0.249642 0.249642)
							(end -0.1778 0.2794)
						)
						(arc
							(start 0.1778 0.2794)
							(mid 0.249642 0.249642)
							(end 0.2794 0.1778)
						)
						(arc
							(start 0.2794 -0.1778)
							(mid 0.249642 -0.249642)
							(end 0.1778 -0.2794)
						)
					)
					(width 0)
					(fill yes)
				)
			)
		)
		(pad "2" smd custom
			(at 0 0.4445 180)
			(size 0.1397 0.1397)
			(layers "F.Cu" "F.Mask" "F.Paste")
			(net "GND")
			(options
				(clearance outline)
				(anchor circle)
			)
			(primitives
				(gr_poly
					(pts
						(arc
							(start -0.1778 -0.2794)
							(mid -0.249642 -0.249642)
							(end -0.2794 -0.1778)
						)
						(arc
							(start -0.2794 0.1778)
							(mid -0.249642 0.249642)
							(end -0.1778 0.2794)
						)
						(arc
							(start 0.1778 0.2794)
							(mid 0.249642 0.249642)
							(end 0.2794 0.1778)
						)
						(arc
							(start 0.2794 -0.1778)
							(mid 0.249642 -0.249642)
							(end 0.1778 -0.2794)
						)
					)
					(width 0)
					(fill yes)
				)
			)
		)
	)
	(footprint ""
		(layer "F.Cu")
		(at 92.070936 -50.398426 180)
		(property "Reference" "R502"
			(at 0 0 180)
			(layer "F.SilkS")
			(hide yes)
			(effects
				(font
					(size 1.27 1.27)
				)
			)
		)
		(property "Value" "1MR2F-GP"
			(at 0.064008 -3.993896 180)
			(unlocked yes)
			(layer "F.Fab")
			(hide yes)
			(effects
				(font
					(size 1.016 1.016)
					(thickness 0.1524)
				)
			)
		)
		(property "Device Type" "R402H16"
			(at 0.064008 -5.517896 180)
			(unlocked yes)
			(layer "F.Fab")
			(hide yes)
			(effects
				(font
					(size 1.016 1.016)
					(thickness 0.1524)
				)
			)
		)
		(duplicate_pad_numbers_are_jumpers no)
		(fp_line
			(start 0.508 -0.9398)
			(end -0.508 -0.9398)
			(stroke
				(width 0.1524)
				(type default)
			)
			(layer "F.SilkS")
		)
		(fp_line
			(start -0.508 -0.9398)
			(end -0.508 0.9398)
			(stroke
				(width 0.1524)
				(type default)
			)
			(layer "F.SilkS")
		)
		(fp_rect
			(start -0.508 0.9398)
			(end 0.508 -0.9398)
			(stroke
				(width 0)
				(type default)
			)
			(fill no)
			(layer "F.CrtYd")
		)
		(fp_rect
			(start -0.508 0.9398)
			(end 0.508 -0.9398)
			(stroke
				(width 0)
				(type default)
			)
			(fill no)
			(layer "F.Fab")
		)
		(pad "1" smd custom
			(at 0 -0.4445 180)
			(size 0.1397 0.1397)
			(layers "F.Cu" "F.Mask" "F.Paste")
			(net "PQ2_D")
			(options
				(clearance outline)
				(anchor circle)
			)
			(primitives
				(gr_poly
					(pts
						(arc
							(start -0.1778 -0.2794)
							(mid -0.249642 -0.249642)
							(end -0.2794 -0.1778)
						)
						(arc
							(start -0.2794 0.1778)
							(mid -0.249642 0.249642)
							(end -0.1778 0.2794)
						)
						(arc
							(start 0.1778 0.2794)
							(mid 0.249642 0.249642)
							(end 0.2794 0.1778)
						)
						(arc
							(start 0.2794 -0.1778)
							(mid 0.249642 -0.249642)
							(end 0.1778 -0.2794)
						)
					)
					(width 0)
					(fill yes)
				)
			)
		)
		(pad "2" smd custom
			(at 0 0.4445 180)
			(size 0.1397 0.1397)
			(layers "F.Cu" "F.Mask" "F.Paste")
			(net "P12V_STBY")
			(options
				(clearance outline)
				(anchor circle)
			)
			(primitives
				(gr_poly
					(pts
						(arc
							(start -0.1778 -0.2794)
							(mid -0.249642 -0.249642)
							(end -0.2794 -0.1778)
						)
						(arc
							(start -0.2794 0.1778)
							(mid -0.249642 0.249642)
							(end -0.1778 0.2794)
						)
						(arc
							(start 0.1778 0.2794)
							(mid 0.249642 0.249642)
							(end 0.2794 0.1778)
						)
						(arc
							(start 0.2794 -0.1778)
							(mid 0.249642 -0.249642)
							(end 0.1778 -0.2794)
						)
					)
					(width 0)
					(fill yes)
				)
			)
		)
	)
	(footprint ""
		(layer "F.Cu")
		(at 28.194 -154.686 -90)
		(property "Reference" "R770"
			(at 0 0 270)
			(layer "F.SilkS")
			(hide yes)
			(effects
				(font
					(size 1.27 1.27)
				)
			)
		)
		(property "Value" "0R2J-2-GP"
			(at 0.064008 -3.993896 270)
			(unlocked yes)
			(layer "F.Fab")
			(hide yes)
			(effects
				(font
					(size 1.016 1.016)
					(thickness 0.1524)
				)
			)
		)
		(property "Device Type" "R402H16"
			(at 0.064008 -5.517896 270)
			(unlocked yes)
			(layer "F.Fab")
			(hide yes)
			(effects
				(font
					(size 1.016 1.016)
					(thickness 0.1524)
				)
			)
		)
		(duplicate_pad_numbers_are_jumpers no)
		(fp_line
			(start -0.508 -0.9398)
			(end -0.508 0.9398)
			(stroke
				(width 0.1524)
				(type default)
			)
			(layer "F.SilkS")
		)
		(fp_line
			(start 0.508 -0.9398)
			(end -0.508 -0.9398)
			(stroke
				(width 0.1524)
				(type default)
			)
			(layer "F.SilkS")
		)
		(fp_rect
			(start -0.508 0.9398)
			(end 0.508 -0.9398)
			(stroke
				(width 0)
				(type default)
			)
			(fill no)
			(layer "F.CrtYd")
		)
		(fp_rect
			(start -0.508 0.9398)
			(end 0.508 -0.9398)
			(stroke
				(width 0)
				(type default)
			)
			(fill no)
			(layer "F.Fab")
		)
		(pad "1" smd custom
			(at 0 -0.4445 270)
			(size 0.1397 0.1397)
			(layers "F.Cu" "F.Mask" "F.Paste")
			(net "DEBUG_GPIO_BMC_R_3")
			(options
				(clearance outline)
				(anchor circle)
			)
			(primitives
				(gr_poly
					(pts
						(arc
							(start -0.1778 -0.2794)
							(mid -0.249642 -0.249642)
							(end -0.2794 -0.1778)
						)
						(arc
							(start -0.2794 0.1778)
							(mid -0.249642 0.249642)
							(end -0.1778 0.2794)
						)
						(arc
							(start 0.1778 0.2794)
							(mid 0.249642 0.249642)
							(end 0.2794 0.1778)
						)
						(arc
							(start 0.2794 -0.1778)
							(mid 0.249642 -0.249642)
							(end 0.1778 -0.2794)
						)
					)
					(width 0)
					(fill yes)
				)
			)
		)
		(pad "2" smd custom
			(at 0 0.4445 270)
			(size 0.1397 0.1397)
			(layers "F.Cu" "F.Mask" "F.Paste")
			(net "DEBUG_GPIO_BMC_3")
			(options
				(clearance outline)
				(anchor circle)
			)
			(primitives
				(gr_poly
					(pts
						(arc
							(start -0.1778 -0.2794)
							(mid -0.249642 -0.249642)
							(end -0.2794 -0.1778)
						)
						(arc
							(start -0.2794 0.1778)
							(mid -0.249642 0.249642)
							(end -0.1778 0.2794)
						)
						(arc
							(start 0.1778 0.2794)
							(mid 0.249642 0.249642)
							(end 0.2794 0.1778)
						)
						(arc
							(start 0.2794 -0.1778)
							(mid 0.249642 -0.249642)
							(end 0.1778 -0.2794)
						)
					)
					(width 0)
					(fill yes)
				)
			)
		)
	)
	(footprint ""
		(layer "F.Cu")
		(at 25.6794 -130.4544 180)
		(property "Reference" "R231"
			(at 0 0 180)
			(layer "F.SilkS")
			(hide yes)
			(effects
				(font
					(size 1.27 1.27)
				)
			)
		)
		(property "Value" "120R2F-GP"
			(at 0.064008 -3.993896 180)
			(unlocked yes)
			(layer "F.Fab")
			(hide yes)
			(effects
				(font
					(size 1.016 1.016)
					(thickness 0.1524)
				)
			)
		)
		(property "Device Type" "R402H16"
			(at 0.064008 -5.517896 180)
			(unlocked yes)
			(layer "F.Fab")
			(hide yes)
			(effects
				(font
					(size 1.016 1.016)
					(thickness 0.1524)
				)
			)
		)
		(duplicate_pad_numbers_are_jumpers no)
		(fp_line
			(start 0.508 -0.9398)
			(end -0.508 -0.9398)
			(stroke
				(width 0.1524)
				(type default)
			)
			(layer "F.SilkS")
		)
		(fp_line
			(start -0.508 -0.9398)
			(end -0.508 0.9398)
			(stroke
				(width 0.1524)
				(type default)
			)
			(layer "F.SilkS")
		)
		(fp_rect
			(start -0.508 0.9398)
			(end 0.508 -0.9398)
			(stroke
				(width 0)
				(type default)
			)
			(fill no)
			(layer "F.CrtYd")
		)
		(fp_rect
			(start -0.508 0.9398)
			(end 0.508 -0.9398)
			(stroke
				(width 0)
				(type default)
			)
			(fill no)
			(layer "F.Fab")
		)
		(pad "1" smd custom
			(at 0 -0.4445 180)
			(size 0.1397 0.1397)
			(layers "F.Cu" "F.Mask" "F.Paste")
			(net "GND")
			(options
				(clearance outline)
				(anchor circle)
			)
			(primitives
				(gr_poly
					(pts
						(arc
							(start -0.1778 -0.2794)
							(mid -0.249642 -0.249642)
							(end -0.2794 -0.1778)
						)
						(arc
							(start -0.2794 0.1778)
							(mid -0.249642 0.249642)
							(end -0.1778 0.2794)
						)
						(arc
							(start 0.1778 0.2794)
							(mid 0.249642 0.249642)
							(end 0.2794 0.1778)
						)
						(arc
							(start 0.2794 -0.1778)
							(mid 0.249642 -0.249642)
							(end 0.1778 -0.2794)
						)
					)
					(width 0)
					(fill yes)
				)
			)
		)
		(pad "2" smd custom
			(at 0 0.4445 180)
			(size 0.1397 0.1397)
			(layers "F.Cu" "F.Mask" "F.Paste")
			(net "MEMBA_1")
			(options
				(clearance outline)
				(anchor circle)
			)
			(primitives
				(gr_poly
					(pts
						(arc
							(start -0.1778 -0.2794)
							(mid -0.249642 -0.249642)
							(end -0.2794 -0.1778)
						)
						(arc
							(start -0.2794 0.1778)
							(mid -0.249642 0.249642)
							(end -0.1778 0.2794)
						)
						(arc
							(start 0.1778 0.2794)
							(mid 0.249642 0.249642)
							(end 0.2794 0.1778)
						)
						(arc
							(start 0.2794 -0.1778)
							(mid 0.249642 -0.249642)
							(end 0.1778 -0.2794)
						)
					)
					(width 0)
					(fill yes)
				)
			)
		)
	)
	(footprint ""
		(layer "F.Cu")
		(at 87.576914 -69.318124 -90)
		(property "Reference" "R15"
			(at 0 0 270)
			(layer "F.SilkS")
			(hide yes)
			(effects
				(font
					(size 1.27 1.27)
				)
			)
		)
		(property "Value" "0R2J-2-GP"
			(at 0.064008 -3.993896 270)
			(unlocked yes)
			(layer "F.Fab")
			(hide yes)
			(effects
				(font
					(size 1.016 1.016)
					(thickness 0.1524)
				)
			)
		)
		(property "Device Type" "R402H16"
			(at 0.064008 -5.517896 270)
			(unlocked yes)
			(layer "F.Fab")
			(hide yes)
			(effects
				(font
					(size 1.016 1.016)
					(thickness 0.1524)
				)
			)
		)
		(duplicate_pad_numbers_are_jumpers no)
		(fp_line
			(start -0.508 -0.9398)
			(end -0.508 0.9398)
			(stroke
				(width 0.1524)
				(type default)
			)
			(layer "F.SilkS")
		)
		(fp_line
			(start 0.508 -0.9398)
			(end -0.508 -0.9398)
			(stroke
				(width 0.1524)
				(type default)
			)
			(layer "F.SilkS")
		)
		(fp_rect
			(start -0.508 0.9398)
			(end 0.508 -0.9398)
			(stroke
				(width 0)
				(type default)
			)
			(fill no)
			(layer "F.CrtYd")
		)
		(fp_rect
			(start -0.508 0.9398)
			(end 0.508 -0.9398)
			(stroke
				(width 0)
				(type default)
			)
			(fill no)
			(layer "F.Fab")
		)
		(pad "1" smd custom
			(at 0 -0.4445 270)
			(size 0.1397 0.1397)
			(layers "F.Cu" "F.Mask" "F.Paste")
			(net "NCSI_RXD1")
			(options
				(clearance outline)
				(anchor circle)
			)
			(primitives
				(gr_poly
					(pts
						(arc
							(start -0.1778 -0.2794)
							(mid -0.249642 -0.249642)
							(end -0.2794 -0.1778)
						)
						(arc
							(start -0.2794 0.1778)
							(mid -0.249642 0.249642)
							(end -0.1778 0.2794)
						)
						(arc
							(start 0.1778 0.2794)
							(mid 0.249642 0.249642)
							(end 0.2794 0.1778)
						)
						(arc
							(start 0.2794 -0.1778)
							(mid 0.249642 -0.249642)
							(end 0.1778 -0.2794)
						)
					)
					(width 0)
					(fill yes)
				)
			)
		)
		(pad "2" smd custom
			(at 0 0.4445 270)
			(size 0.1397 0.1397)
			(layers "F.Cu" "F.Mask" "F.Paste")
			(net "NCSI_RXD1_R")
			(options
				(clearance outline)
				(anchor circle)
			)
			(primitives
				(gr_poly
					(pts
						(arc
							(start -0.1778 -0.2794)
							(mid -0.249642 -0.249642)
							(end -0.2794 -0.1778)
						)
						(arc
							(start -0.2794 0.1778)
							(mid -0.249642 0.249642)
							(end -0.1778 0.2794)
						)
						(arc
							(start 0.1778 0.2794)
							(mid 0.249642 0.249642)
							(end 0.2794 0.1778)
						)
						(arc
							(start 0.2794 -0.1778)
							(mid 0.249642 -0.249642)
							(end 0.1778 -0.2794)
						)
					)
					(width 0)
					(fill yes)
				)
			)
		)
	)
)
